(kicad_pcb
	(version 20260206)
	(generator "pcbnew")
	(generator_version "10.0")
	(general
		(thickness 1.6)
		(legacy_teardrops no)
	)
	(paper "A4")
	(title_block
		(title "9054_F0T_PDB_BD_GPU_F_V04_1213_1550_OCP.brd")
		(comment 1 "Grand Teton / footprints 168-173 of 608")
	)
	(layers
		(0 "F.Cu" signal "TOP")
		(4 "In1.Cu" signal "GND")
		(6 "In2.Cu" signal "IN1")
		(8 "In3.Cu" signal "GND1")
		(10 "In4.Cu" signal "VCC")
		(12 "In5.Cu" signal "VCC1")
		(14 "In6.Cu" signal "GND2")
		(16 "In7.Cu" signal "IN2")
		(18 "In8.Cu" signal "GND3")
		(2 "B.Cu" signal "BOTTOM")
		(9 "F.Adhes" user "F.Adhesive")
		(11 "B.Adhes" user "B.Adhesive")
		(13 "F.Paste" user "Package Geometry/Pastemask Top")
		(15 "B.Paste" user "Package Geometry/Pastemask Bottom")
		(5 "F.SilkS" user "Ref Des/Silkscreen Top")
		(7 "B.SilkS" user "Ref Des/Silkscreen Bottom")
		(1 "F.Mask" user "Board Geometry/Soldermask Top")
		(3 "B.Mask" user "Board Geometry/Soldermask Bottom")
		(17 "Dwgs.User" user "User.Drawings")
		(19 "Cmts.User" user "User.Comments")
		(21 "Eco1.User" user "User.Eco1")
		(23 "Eco2.User" user "User.Eco2")
		(25 "Edge.Cuts" user "Board Geometry/Outline")
		(27 "Margin" user)
		(31 "F.CrtYd" user "Package Geometry/Place Bound Top")
		(29 "B.CrtYd" user "Package Geometry/Place Bound Bottom")
		(35 "F.Fab" user "Ref Des/Assembly Top")
		(33 "B.Fab" user "Ref Des/Assembly Bottom")
	)
	(footprint ""
		(layer "F.Cu")
		(at 52.832 -29.718 90)
		(property "Reference" "PR105"
			(at 0 0 90)
			(layer "F.SilkS")
			(hide yes)
			(effects
				(font
					(size 1.27 1.27)
				)
			)
		)
		(property "Value" ""
			(at 0 0 90)
			(layer "F.Fab")
			(effects
				(font
					(size 1.27 1.27)
				)
			)
		)
		(duplicate_pad_numbers_are_jumpers no)
		(fp_line
			(start 0.7874 -0.4064)
			(end 0.7874 0.4064)
			(stroke
				(width 0.1524)
				(type default)
			)
			(layer "F.SilkS")
		)
		(fp_line
			(start -0.7874 -0.4064)
			(end 0.7874 -0.4064)
			(stroke
				(width 0.1524)
				(type default)
			)
			(layer "F.SilkS")
		)
		(fp_line
			(start 0.7874 0.4064)
			(end -0.7874 0.4064)
			(stroke
				(width 0.1524)
				(type default)
			)
			(layer "F.SilkS")
		)
		(fp_line
			(start -0.7874 0.4064)
			(end -0.7874 -0.4064)
			(stroke
				(width 0.1524)
				(type default)
			)
			(layer "F.SilkS")
		)
		(fp_line
			(start -0.12065 -0.305054)
			(end -0.12065 -0.2794)
			(stroke
				(width 0.1)
				(type default)
			)
			(layer "F.Fab")
		)
		(fp_line
			(start -0.67945 -0.305054)
			(end -0.12065 -0.305054)
			(stroke
				(width 0.1)
				(type default)
			)
			(layer "F.Fab")
		)
		(fp_line
			(start 0.67945 -0.3048)
			(end 0.67945 0.3048)
			(stroke
				(width 0.1)
				(type default)
			)
			(layer "F.Fab")
		)
		(fp_line
			(start 0.12065 -0.3048)
			(end 0.67945 -0.3048)
			(stroke
				(width 0.1)
				(type default)
			)
			(layer "F.Fab")
		)
		(fp_line
			(start 0.12065 -0.2794)
			(end 0.12065 -0.3048)
			(stroke
				(width 0.1)
				(type default)
			)
			(layer "F.Fab")
		)
		(fp_line
			(start -0.12065 -0.2794)
			(end 0.12065 -0.2794)
			(stroke
				(width 0.1)
				(type default)
			)
			(layer "F.Fab")
		)
		(fp_line
			(start 0.120396 0.2794)
			(end -0.12065 0.2794)
			(stroke
				(width 0.1)
				(type default)
			)
			(layer "F.Fab")
		)
		(fp_line
			(start -0.12065 0.2794)
			(end -0.12065 0.3048)
			(stroke
				(width 0.1)
				(type default)
			)
			(layer "F.Fab")
		)
		(fp_line
			(start 0.67945 0.3048)
			(end 0.120396 0.3048)
			(stroke
				(width 0.1)
				(type default)
			)
			(layer "F.Fab")
		)
		(fp_line
			(start 0.120396 0.3048)
			(end 0.120396 0.2794)
			(stroke
				(width 0.1)
				(type default)
			)
			(layer "F.Fab")
		)
		(fp_line
			(start -0.12065 0.3048)
			(end -0.67945 0.3048)
			(stroke
				(width 0.1)
				(type default)
			)
			(layer "F.Fab")
		)
		(fp_line
			(start -0.67945 0.3048)
			(end -0.67945 -0.305054)
			(stroke
				(width 0.1)
				(type default)
			)
			(layer "F.Fab")
		)
		(pad "1" smd circle
			(at -0.40005 0 90)
			(size 0 0)
			(layers "F.Cu" "F.Mask" "F.Paste")
			(net "P52V_HS2_EN_DISCHARGE_VBE")
		)
		(pad "2" smd circle
			(at 0.40005 0 90)
			(size 0 0)
			(layers "F.Cu" "F.Mask" "F.Paste")
			(net "P52V_HS2_EN_DISCHARGE_VBE_R")
		)
	)
	(footprint ""
		(layer "F.Cu")
		(at 406.146 -30.988)
		(property "Reference" "R46"
			(at 0 0 0)
			(layer "F.SilkS")
			(hide yes)
			(effects
				(font
					(size 1.27 1.27)
				)
			)
		)
		(property "Value" ""
			(at 0 0 0)
			(layer "F.Fab")
			(effects
				(font
					(size 1.27 1.27)
				)
			)
		)
		(duplicate_pad_numbers_are_jumpers no)
		(fp_line
			(start -2.234946 -0.9271)
			(end 2.234946 -0.9271)
			(stroke
				(width 0.1524)
				(type default)
			)
			(layer "F.SilkS")
		)
		(fp_line
			(start -2.234946 0.9271)
			(end -2.234946 -0.9271)
			(stroke
				(width 0.1524)
				(type default)
			)
			(layer "F.SilkS")
		)
		(fp_line
			(start 2.234946 -0.9271)
			(end 2.234946 0.9271)
			(stroke
				(width 0.1524)
				(type default)
			)
			(layer "F.SilkS")
		)
		(fp_line
			(start 2.234946 0.9271)
			(end -2.234946 0.9271)
			(stroke
				(width 0.1524)
				(type default)
			)
			(layer "F.SilkS")
		)
		(fp_line
			(start -1.575054 -0.824992)
			(end -1.575054 0.824992)
			(stroke
				(width 0.1)
				(type default)
			)
			(layer "F.Fab")
		)
		(fp_line
			(start -1.575054 0.824992)
			(end 1.575054 0.824992)
			(stroke
				(width 0.1)
				(type default)
			)
			(layer "F.Fab")
		)
		(fp_line
			(start 1.575054 -0.824992)
			(end -1.575054 -0.824992)
			(stroke
				(width 0.1)
				(type default)
			)
			(layer "F.Fab")
		)
		(fp_line
			(start 1.575054 0.824992)
			(end 1.575054 -0.824992)
			(stroke
				(width 0.1)
				(type default)
			)
			(layer "F.Fab")
		)
		(pad "1" smd rect
			(at -1.599946 0)
			(size 1.016 1.6002)
			(layers "F.Cu" "F.Mask" "F.Paste")
			(net "LED_D1_R4")
		)
		(pad "2" smd rect
			(at 1.599946 0)
			(size 1.016 1.6002)
			(layers "F.Cu" "F.Mask" "F.Paste")
			(net "LED_D1_R5")
		)
	)
	(footprint ""
		(layer "F.Cu")
		(at 431.4444 -24.6126 90)
		(property "Reference" "U9"
			(at 0.1524 -3.27533 90)
			(unlocked yes)
			(layer "F.SilkS")
			(effects
				(font
					(size 0.7874 0.5842)
					(thickness 0.1524)
				)
				(justify left)
			)
		)
		(property "Value" ""
			(at 0 0 90)
			(layer "F.Fab")
			(effects
				(font
					(size 1.27 1.27)
				)
			)
		)
		(duplicate_pad_numbers_are_jumpers no)
		(fp_line
			(start 1.4224 -2.5146)
			(end 0.4572 -2.5146)
			(stroke
				(width 0.1524)
				(type default)
			)
			(layer "F.SilkS")
		)
		(fp_line
			(start 0.4572 -2.5146)
			(end 0 -2.0574)
			(stroke
				(width 0.1524)
				(type default)
			)
			(layer "F.SilkS")
		)
		(fp_line
			(start -0.4572 -2.5146)
			(end -1.4224 -2.5146)
			(stroke
				(width 0.1524)
				(type default)
			)
			(layer "F.SilkS")
		)
		(fp_line
			(start -1.4224 -2.5146)
			(end -1.4224 2.5146)
			(stroke
				(width 0.1524)
				(type default)
			)
			(layer "F.SilkS")
		)
		(fp_line
			(start 0 -2.0574)
			(end -0.4572 -2.5146)
			(stroke
				(width 0.1524)
				(type default)
			)
			(layer "F.SilkS")
		)
		(fp_line
			(start 1.4224 2.5146)
			(end 1.4224 -2.5146)
			(stroke
				(width 0.1524)
				(type default)
			)
			(layer "F.SilkS")
		)
		(fp_line
			(start -1.4224 2.5146)
			(end 1.4224 2.5146)
			(stroke
				(width 0.1524)
				(type default)
			)
			(layer "F.SilkS")
		)
		(fp_poly
			(pts
				(xy -2.804414 -2.3876) (xy -3.185414 -3.1496) (xy -2.423414 -3.1496)
			)
			(stroke
				(width 0)
				(type default)
			)
			(fill yes)
			(layer "F.SilkS")
		)
		(fp_line
			(start 2.0066 -2.5146)
			(end -2.0066 -2.5146)
			(stroke
				(width 0.1)
				(type default)
			)
			(layer "F.Fab")
		)
		(fp_line
			(start -2.0066 -2.5146)
			(end -2.0066 -2.114804)
			(stroke
				(width 0.1)
				(type default)
			)
			(layer "F.Fab")
		)
		(fp_line
			(start -2.0066 -2.114804)
			(end -2.648712 -2.114804)
			(stroke
				(width 0.1)
				(type default)
			)
			(layer "F.Fab")
		)
		(fp_line
			(start -2.648712 -2.114804)
			(end -2.648712 2.112264)
			(stroke
				(width 0.1)
				(type default)
			)
			(layer "F.Fab")
		)
		(fp_line
			(start 2.642616 -2.112264)
			(end 2.0066 -2.112264)
			(stroke
				(width 0.1)
				(type default)
			)
			(layer "F.Fab")
		)
		(fp_line
			(start 2.0066 -2.112264)
			(end 2.0066 -2.5146)
			(stroke
				(width 0.1)
				(type default)
			)
			(layer "F.Fab")
		)
		(fp_line
			(start 2.642616 2.112264)
			(end 2.642616 -2.112264)
			(stroke
				(width 0.1)
				(type default)
			)
			(layer "F.Fab")
		)
		(fp_line
			(start 2.0066 2.112264)
			(end 2.642616 2.112264)
			(stroke
				(width 0.1)
				(type default)
			)
			(layer "F.Fab")
		)
		(fp_line
			(start -2.0066 2.112264)
			(end -2.0066 2.5146)
			(stroke
				(width 0.1)
				(type default)
			)
			(layer "F.Fab")
		)
		(fp_line
			(start -2.648712 2.112264)
			(end -2.0066 2.112264)
			(stroke
				(width 0.1)
				(type default)
			)
			(layer "F.Fab")
		)
		(fp_line
			(start 2.0066 2.5146)
			(end 2.0066 2.112264)
			(stroke
				(width 0.1)
				(type default)
			)
			(layer "F.Fab")
		)
		(fp_line
			(start -2.0066 2.5146)
			(end 2.0066 2.5146)
			(stroke
				(width 0.1)
				(type default)
			)
			(layer "F.Fab")
		)
		(fp_poly
			(pts
				(xy -3.6322 -1.869186) (xy -4.3942 -1.488186) (xy -4.3942 -2.250186)
			)
			(stroke
				(width 0)
				(type default)
			)
			(fill yes)
			(layer "F.Fab")
		)
		(pad "1" smd rect
			(at -2.6416 -1.905)
			(size 0.5588 1.7272)
			(layers "F.Cu" "F.Mask" "F.Paste")
			(net "FRU_ADDR0")
		)
		(pad "2" smd rect
			(at -2.6416 -0.635)
			(size 0.5588 1.7272)
			(layers "F.Cu" "F.Mask" "F.Paste")
			(net "FRU_ADDR1")
		)
		(pad "3" smd rect
			(at -2.6416 0.635)
			(size 0.5588 1.7272)
			(layers "F.Cu" "F.Mask" "F.Paste")
			(net "FRU_ADDR2")
		)
		(pad "4" smd rect
			(at -2.6416 1.905)
			(size 0.5588 1.7272)
			(layers "F.Cu" "F.Mask" "F.Paste")
			(net "GND")
		)
		(pad "5" smd rect
			(at 2.6416 1.905)
			(size 0.5588 1.7272)
			(layers "F.Cu" "F.Mask" "F.Paste")
			(net "SMB_FRU_DAT")
		)
		(pad "6" smd rect
			(at 2.6416 0.635)
			(size 0.5588 1.7272)
			(layers "F.Cu" "F.Mask" "F.Paste")
			(net "SMB_FRU_CLK")
		)
		(pad "7" smd rect
			(at 2.6416 -0.635)
			(size 0.5588 1.7272)
			(layers "F.Cu" "F.Mask" "F.Paste")
			(net "FRU_WP_N")
		)
		(pad "8" smd rect
			(at 2.6416 -1.905)
			(size 0.5588 1.7272)
			(layers "F.Cu" "F.Mask" "F.Paste")
			(net "P3V3_AUX")
		)
	)
	(footprint ""
		(layer "F.Cu")
		(at 112.988852 -55.372 -90)
		(property "Reference" "PR6972"
			(at 0 0 270)
			(layer "F.SilkS")
			(hide yes)
			(effects
				(font
					(size 1.27 1.27)
				)
			)
		)
		(property "Value" ""
			(at 0 0 270)
			(layer "F.Fab")
			(effects
				(font
					(size 1.27 1.27)
				)
			)
		)
		(duplicate_pad_numbers_are_jumpers no)
		(fp_line
			(start -1.2954 0.5842)
			(end -1.2954 -0.5842)
			(stroke
				(width 0.1524)
				(type default)
			)
			(layer "F.SilkS")
		)
		(fp_line
			(start 1.2954 0.5842)
			(end -1.2954 0.5842)
			(stroke
				(width 0.1524)
				(type default)
			)
			(layer "F.SilkS")
		)
		(fp_line
			(start -1.2954 -0.5842)
			(end 1.2954 -0.5842)
			(stroke
				(width 0.1524)
				(type default)
			)
			(layer "F.SilkS")
		)
		(fp_line
			(start 1.2954 -0.5842)
			(end 1.2954 0.5842)
			(stroke
				(width 0.1524)
				(type default)
			)
			(layer "F.SilkS")
		)
		(fp_line
			(start -0.8636 0.4572)
			(end -0.8636 0.4318)
			(stroke
				(width 0.1)
				(type default)
			)
			(layer "F.Fab")
		)
		(fp_line
			(start 0.8636 0.4572)
			(end -0.8636 0.4572)
			(stroke
				(width 0.1)
				(type default)
			)
			(layer "F.Fab")
		)
		(fp_line
			(start -0.8636 0.4318)
			(end -0.8636 0.4064)
			(stroke
				(width 0.1)
				(type default)
			)
			(layer "F.Fab")
		)
		(fp_line
			(start -1.1938 0.4064)
			(end -1.1938 -0.406654)
			(stroke
				(width 0.1)
				(type default)
			)
			(layer "F.Fab")
		)
		(fp_line
			(start -0.8636 0.4064)
			(end -1.1938 0.4064)
			(stroke
				(width 0.1)
				(type default)
			)
			(layer "F.Fab")
		)
		(fp_line
			(start 0.8636 0.4064)
			(end 0.8636 0.4572)
			(stroke
				(width 0.1)
				(type default)
			)
			(layer "F.Fab")
		)
		(fp_line
			(start 1.1938 0.4064)
			(end 0.8636 0.4064)
			(stroke
				(width 0.1)
				(type default)
			)
			(layer "F.Fab")
		)
		(fp_line
			(start -1.1938 -0.406654)
			(end -0.8636 -0.406654)
			(stroke
				(width 0.1)
				(type default)
			)
			(layer "F.Fab")
		)
		(fp_line
			(start -0.8636 -0.406654)
			(end -0.8636 -0.4572)
			(stroke
				(width 0.1)
				(type default)
			)
			(layer "F.Fab")
		)
		(fp_line
			(start 0.8636 -0.406654)
			(end 1.1938 -0.406654)
			(stroke
				(width 0.1)
				(type default)
			)
			(layer "F.Fab")
		)
		(fp_line
			(start 1.1938 -0.406654)
			(end 1.1938 0.4064)
			(stroke
				(width 0.1)
				(type default)
			)
			(layer "F.Fab")
		)
		(fp_line
			(start -0.8636 -0.4572)
			(end 0.8636 -0.4572)
			(stroke
				(width 0.1)
				(type default)
			)
			(layer "F.Fab")
		)
		(fp_line
			(start 0.8636 -0.4572)
			(end 0.8636 -0.406654)
			(stroke
				(width 0.1)
				(type default)
			)
			(layer "F.Fab")
		)
		(pad "1" smd rect
			(at -0.7366 0 180)
			(size 0.7112 0.8128)
			(layers "F.Cu" "F.Mask" "F.Paste")
			(net "P52V_HS2_GATE1_R")
		)
		(pad "2" smd rect
			(at 0.7366 0 180)
			(size 0.7112 0.8128)
			(layers "F.Cu" "F.Mask" "F.Paste")
			(net "P52V_HS2_GATE3")
		)
	)
	(footprint ""
		(layer "F.Cu")
		(at 317.2079 -85.598)
		(property "Reference" "PR6966"
			(at 0 0 0)
			(layer "F.SilkS")
			(hide yes)
			(effects
				(font
					(size 1.27 1.27)
				)
			)
		)
		(property "Value" ""
			(at 0 0 0)
			(layer "F.Fab")
			(effects
				(font
					(size 1.27 1.27)
				)
			)
		)
		(duplicate_pad_numbers_are_jumpers no)
		(fp_line
			(start -0.7874 -0.4064)
			(end 0.7874 -0.4064)
			(stroke
				(width 0.1524)
				(type default)
			)
			(layer "F.SilkS")
		)
		(fp_line
			(start -0.7874 0.4064)
			(end -0.7874 -0.4064)
			(stroke
				(width 0.1524)
				(type default)
			)
			(layer "F.SilkS")
		)
		(fp_line
			(start 0.7874 -0.4064)
			(end 0.7874 0.4064)
			(stroke
				(width 0.1524)
				(type default)
			)
			(layer "F.SilkS")
		)
		(fp_line
			(start 0.7874 0.4064)
			(end -0.7874 0.4064)
			(stroke
				(width 0.1524)
				(type default)
			)
			(layer "F.SilkS")
		)
		(fp_line
			(start -0.67945 -0.305054)
			(end -0.12065 -0.305054)
			(stroke
				(width 0.1)
				(type default)
			)
			(layer "F.Fab")
		)
		(fp_line
			(start -0.67945 0.3048)
			(end -0.67945 -0.305054)
			(stroke
				(width 0.1)
				(type default)
			)
			(layer "F.Fab")
		)
		(fp_line
			(start -0.12065 -0.305054)
			(end -0.12065 -0.2794)
			(stroke
				(width 0.1)
				(type default)
			)
			(layer "F.Fab")
		)
		(fp_line
			(start -0.12065 -0.2794)
			(end 0.12065 -0.2794)
			(stroke
				(width 0.1)
				(type default)
			)
			(layer "F.Fab")
		)
		(fp_line
			(start -0.12065 0.2794)
			(end -0.12065 0.3048)
			(stroke
				(width 0.1)
				(type default)
			)
			(layer "F.Fab")
		)
		(fp_line
			(start -0.12065 0.3048)
			(end -0.67945 0.3048)
			(stroke
				(width 0.1)
				(type default)
			)
			(layer "F.Fab")
		)
		(fp_line
			(start 0.120396 0.2794)
			(end -0.12065 0.2794)
			(stroke
				(width 0.1)
				(type default)
			)
			(layer "F.Fab")
		)
		(fp_line
			(start 0.120396 0.3048)
			(end 0.120396 0.2794)
			(stroke
				(width 0.1)
				(type default)
			)
			(layer "F.Fab")
		)
		(fp_line
			(start 0.12065 -0.3048)
			(end 0.67945 -0.3048)
			(stroke
				(width 0.1)
				(type default)
			)
			(layer "F.Fab")
		)
		(fp_line
			(start 0.12065 -0.2794)
			(end 0.12065 -0.3048)
			(stroke
				(width 0.1)
				(type default)
			)
			(layer "F.Fab")
		)
		(fp_line
			(start 0.67945 -0.3048)
			(end 0.67945 0.3048)
			(stroke
				(width 0.1)
				(type default)
			)
			(layer "F.Fab")
		)
		(fp_line
			(start 0.67945 0.3048)
			(end 0.120396 0.3048)
			(stroke
				(width 0.1)
				(type default)
			)
			(layer "F.Fab")
		)
		(pad "1" smd rect
			(at -0.40005 0 180)
			(size 0.4572 0.508)
			(layers "F.Cu" "F.Mask" "F.Paste")
			(net "P52V_HS1_TEMP")
		)
		(pad "2" smd rect
			(at 0.40005 0 180)
			(size 0.4572 0.508)
			(layers "F.Cu" "F.Mask" "F.Paste")
			(net "P52V_HS1_TEMP_R")
		)
	)
	(footprint ""
		(layer "F.Cu")
		(at 95.25 -45.9486)
		(property "Reference" "ME2"
			(at 0 0 0)
			(layer "F.SilkS")
			(hide yes)
			(effects
				(font
					(size 1.27 1.27)
				)
			)
		)
		(property "Value" ""
			(at 0 0 0)
			(layer "F.Fab")
			(effects
				(font
					(size 1.27 1.27)
				)
			)
		)
		(duplicate_pad_numbers_are_jumpers no)
		(fp_poly
			(pts
				(xy 0 -0.5842) (xy 3.3401 -0.5842) (xy 3.3401 0) (xy 0 0)
			)
			(stroke
				(width 0)
				(type default)
			)
			(fill yes)
			(layer "F.SilkS")
		)
		(fp_poly
			(pts
				(xy 1.32715 -3.4417) (xy 2.01295 -3.4417) (xy 2.01295 -3.2512) (xy 1.32715 -3.2512)
			)
			(stroke
				(width 0)
				(type default)
			)
			(fill yes)
			(layer "F.SilkS")
		)
		(fp_poly
			(pts
				(xy -0.070612 -0.681228) (xy -0.197612 -0.820928) (xy 0.852678 -1.91262) (xy 0.728472 -3.29184)
				(xy -0.248412 -4.300728) (xy -0.184912 -4.478528) (xy -0.007112 -4.503928) (xy 0.684022 -3.785616)
				(xy 0.65659 -4.0894) (xy 0.97155 -4.3434) (xy 1.22555 -4.3561) (xy 1.46685 -4.4704) (xy 2.01295 -4.4704)
				(xy 2.15265 -4.4069) (xy 2.44475 -4.191) (xy 2.49555 -4.191) (xy 2.59715 -4.2926) (xy 2.80035 -4.2672)
				(xy 2.88925 -4.1656) (xy 2.88925 -4.029456) (xy 3.345688 -4.503928) (xy 3.523488 -4.478528) (xy 3.586988 -4.300728)
				(xy 2.88925 -3.58013) (xy 2.88925 -3.3147) (xy 2.82575 -3.2385) (xy 2.67335 -3.2385) (xy 2.521966 -1.875282)
				(xy 2.545842 -1.85039)
				(arc
					(start 2.55905 -1.8415)
					(mid 2.648099 -1.766068)
					(end 2.717292 -1.672082)
				)
				(xy 3.536188 -0.820928) (xy 3.409188 -0.681228) (xy 3.244088 -0.693928)
				(arc
					(start 2.737612 -1.216914)
					(mid 2.31728 -0.925553)
					(end 1.86055 -1.1557)
				)
				(xy 0.92075 -1.1557) (xy 0.888492 -1.51384) (xy 0.094488 -0.693928)
			)
			(stroke
				(width 0)
				(type default)
			)
			(fill yes)
			(layer "F.SilkS")
		)
	)
)
